(kicad_pcb
	(version 20260206)
	(generator "pcbnew")
	(generator_version "10.0")
	(general
		(thickness 1.6)
		(legacy_teardrops no)
	)
	(paper "A4")
	(title_block
		(title "01162023_DA0F0TEBIF0_F0T_Expander_BD_F_brd_V02_OCP.brd")
		(comment 1 "Grand Teton / footprints 6494-6500 of 9728")
	)
	(layers
		(0 "F.Cu" signal "TOP")
		(4 "In1.Cu" signal "GND")
		(6 "In2.Cu" signal "VCC")
		(8 "In3.Cu" signal "VCC1")
		(10 "In4.Cu" signal "GND1")
		(12 "In5.Cu" signal "IN1")
		(14 "In6.Cu" signal "GND2")
		(16 "In7.Cu" signal "IN2")
		(18 "In8.Cu" signal "GND3")
		(20 "In9.Cu" signal "IN3")
		(22 "In10.Cu" signal "GND4")
		(24 "In11.Cu" signal "IN4")
		(26 "In12.Cu" signal "GND5")
		(28 "In13.Cu" signal "IN5")
		(30 "In14.Cu" signal "GND6")
		(32 "In15.Cu" signal "IN6")
		(34 "In16.Cu" signal "GND7")
		(2 "B.Cu" signal "BOTTOM")
		(9 "F.Adhes" user "F.Adhesive")
		(11 "B.Adhes" user "B.Adhesive")
		(13 "F.Paste" user "Package Geometry/Pastemask Top")
		(15 "B.Paste" user "Package Geometry/Pastemask Bottom")
		(5 "F.SilkS" user "Ref Des/Silkscreen Top")
		(7 "B.SilkS" user "Ref Des/Silkscreen Bottom")
		(1 "F.Mask" user "Board Geometry/Soldermask Top")
		(3 "B.Mask" user "Board Geometry/Soldermask Bottom")
		(17 "Dwgs.User" user "User.Drawings")
		(19 "Cmts.User" user "User.Comments")
		(21 "Eco1.User" user "User.Eco1")
		(23 "Eco2.User" user "User.Eco2")
		(25 "Edge.Cuts" user "Board Geometry/Outline")
		(27 "Margin" user)
		(31 "F.CrtYd" user "Package Geometry/Place Bound Top")
		(29 "B.CrtYd" user "Package Geometry/Place Bound Bottom")
		(35 "F.Fab" user "Ref Des/Assembly Top")
		(33 "B.Fab" user "Ref Des/Assembly Bottom")
	)
	(footprint ""
		(layer "F.Cu")
		(at 360.050588 -398.649444)
		(property "Reference" "R6706"
			(at 0 0 0)
			(layer "F.SilkS")
			(hide yes)
			(effects
				(font
					(size 1.27 1.27)
				)
			)
		)
		(property "Value" ""
			(at 0 0 0)
			(layer "F.Fab")
			(effects
				(font
					(size 1.27 1.27)
				)
			)
		)
		(duplicate_pad_numbers_are_jumpers no)
		(fp_line
			(start -0.7874 -0.4064)
			(end 0.7874 -0.4064)
			(stroke
				(width 0.1524)
				(type default)
			)
			(layer "F.SilkS")
		)
		(fp_line
			(start -0.7874 0.4064)
			(end -0.7874 -0.4064)
			(stroke
				(width 0.1524)
				(type default)
			)
			(layer "F.SilkS")
		)
		(fp_line
			(start 0.7874 -0.4064)
			(end 0.7874 0.4064)
			(stroke
				(width 0.1524)
				(type default)
			)
			(layer "F.SilkS")
		)
		(fp_line
			(start 0.7874 0.4064)
			(end -0.7874 0.4064)
			(stroke
				(width 0.1524)
				(type default)
			)
			(layer "F.SilkS")
		)
		(fp_line
			(start -0.67945 -0.305054)
			(end -0.12065 -0.305054)
			(stroke
				(width 0.1)
				(type default)
			)
			(layer "F.Fab")
		)
		(fp_line
			(start -0.67945 0.3048)
			(end -0.67945 -0.305054)
			(stroke
				(width 0.1)
				(type default)
			)
			(layer "F.Fab")
		)
		(fp_line
			(start -0.12065 -0.305054)
			(end -0.12065 -0.2794)
			(stroke
				(width 0.1)
				(type default)
			)
			(layer "F.Fab")
		)
		(fp_line
			(start -0.12065 -0.2794)
			(end 0.12065 -0.2794)
			(stroke
				(width 0.1)
				(type default)
			)
			(layer "F.Fab")
		)
		(fp_line
			(start -0.12065 0.2794)
			(end -0.12065 0.3048)
			(stroke
				(width 0.1)
				(type default)
			)
			(layer "F.Fab")
		)
		(fp_line
			(start -0.12065 0.3048)
			(end -0.67945 0.3048)
			(stroke
				(width 0.1)
				(type default)
			)
			(layer "F.Fab")
		)
		(fp_line
			(start 0.120396 0.2794)
			(end -0.12065 0.2794)
			(stroke
				(width 0.1)
				(type default)
			)
			(layer "F.Fab")
		)
		(fp_line
			(start 0.120396 0.3048)
			(end 0.120396 0.2794)
			(stroke
				(width 0.1)
				(type default)
			)
			(layer "F.Fab")
		)
		(fp_line
			(start 0.12065 -0.3048)
			(end 0.67945 -0.3048)
			(stroke
				(width 0.1)
				(type default)
			)
			(layer "F.Fab")
		)
		(fp_line
			(start 0.12065 -0.2794)
			(end 0.12065 -0.3048)
			(stroke
				(width 0.1)
				(type default)
			)
			(layer "F.Fab")
		)
		(fp_line
			(start 0.67945 -0.3048)
			(end 0.67945 0.3048)
			(stroke
				(width 0.1)
				(type default)
			)
			(layer "F.Fab")
		)
		(fp_line
			(start 0.67945 0.3048)
			(end 0.120396 0.3048)
			(stroke
				(width 0.1)
				(type default)
			)
			(layer "F.Fab")
		)
		(pad "1" smd circle
			(at -0.40005 0)
			(size 0 0)
			(layers "F.Cu" "F.Mask" "F.Paste")
			(net "MB_3V3IO_RSVD3_ISO")
		)
		(pad "2" smd circle
			(at 0.40005 0)
			(size 0 0)
			(layers "F.Cu" "F.Mask" "F.Paste")
			(net "MB_3V3IO_RSVD3")
		)
	)
	(footprint ""
		(layer "F.Cu")
		(at 378.852684 -88.8238)
		(property "Reference" "R1765"
			(at 0 0 0)
			(layer "F.SilkS")
			(hide yes)
			(effects
				(font
					(size 1.27 1.27)
				)
			)
		)
		(property "Value" ""
			(at 0 0 0)
			(layer "F.Fab")
			(effects
				(font
					(size 1.27 1.27)
				)
			)
		)
		(duplicate_pad_numbers_are_jumpers no)
		(fp_line
			(start -0.7874 -0.4064)
			(end 0.7874 -0.4064)
			(stroke
				(width 0.1524)
				(type default)
			)
			(layer "F.SilkS")
		)
		(fp_line
			(start -0.7874 0.4064)
			(end -0.7874 -0.4064)
			(stroke
				(width 0.1524)
				(type default)
			)
			(layer "F.SilkS")
		)
		(fp_line
			(start 0.7874 -0.4064)
			(end 0.7874 0.4064)
			(stroke
				(width 0.1524)
				(type default)
			)
			(layer "F.SilkS")
		)
		(fp_line
			(start 0.7874 0.4064)
			(end -0.7874 0.4064)
			(stroke
				(width 0.1524)
				(type default)
			)
			(layer "F.SilkS")
		)
		(fp_line
			(start -0.67945 -0.305054)
			(end -0.12065 -0.305054)
			(stroke
				(width 0.1)
				(type default)
			)
			(layer "F.Fab")
		)
		(fp_line
			(start -0.67945 0.3048)
			(end -0.67945 -0.305054)
			(stroke
				(width 0.1)
				(type default)
			)
			(layer "F.Fab")
		)
		(fp_line
			(start -0.12065 -0.305054)
			(end -0.12065 -0.2794)
			(stroke
				(width 0.1)
				(type default)
			)
			(layer "F.Fab")
		)
		(fp_line
			(start -0.12065 -0.2794)
			(end 0.12065 -0.2794)
			(stroke
				(width 0.1)
				(type default)
			)
			(layer "F.Fab")
		)
		(fp_line
			(start -0.12065 0.2794)
			(end -0.12065 0.3048)
			(stroke
				(width 0.1)
				(type default)
			)
			(layer "F.Fab")
		)
		(fp_line
			(start -0.12065 0.3048)
			(end -0.67945 0.3048)
			(stroke
				(width 0.1)
				(type default)
			)
			(layer "F.Fab")
		)
		(fp_line
			(start 0.120396 0.2794)
			(end -0.12065 0.2794)
			(stroke
				(width 0.1)
				(type default)
			)
			(layer "F.Fab")
		)
		(fp_line
			(start 0.120396 0.3048)
			(end 0.120396 0.2794)
			(stroke
				(width 0.1)
				(type default)
			)
			(layer "F.Fab")
		)
		(fp_line
			(start 0.12065 -0.3048)
			(end 0.67945 -0.3048)
			(stroke
				(width 0.1)
				(type default)
			)
			(layer "F.Fab")
		)
		(fp_line
			(start 0.12065 -0.2794)
			(end 0.12065 -0.3048)
			(stroke
				(width 0.1)
				(type default)
			)
			(layer "F.Fab")
		)
		(fp_line
			(start 0.67945 -0.3048)
			(end 0.67945 0.3048)
			(stroke
				(width 0.1)
				(type default)
			)
			(layer "F.Fab")
		)
		(fp_line
			(start 0.67945 0.3048)
			(end 0.120396 0.3048)
			(stroke
				(width 0.1)
				(type default)
			)
			(layer "F.Fab")
		)
		(pad "1" smd circle
			(at -0.40005 0)
			(size 0 0)
			(layers "F.Cu" "F.Mask" "F.Paste")
			(net "SMB_BIC_I2C6_MUX_NIC_ADC_R_SDA")
		)
		(pad "2" smd circle
			(at 0.40005 0)
			(size 0 0)
			(layers "F.Cu" "F.Mask" "F.Paste")
			(net "SMB_BIC_I2C6_MUX_NIC_ADC_SDA")
		)
	)
	(footprint ""
		(layer "F.Cu")
		(at 25.358344 -252.356874 -90)
		(property "Reference" "R1203"
			(at 0 0 270)
			(layer "F.SilkS")
			(hide yes)
			(effects
				(font
					(size 1.27 1.27)
				)
			)
		)
		(property "Value" ""
			(at 0 0 270)
			(layer "F.Fab")
			(effects
				(font
					(size 1.27 1.27)
				)
			)
		)
		(duplicate_pad_numbers_are_jumpers no)
		(fp_line
			(start -0.7874 0.4064)
			(end -0.7874 -0.4064)
			(stroke
				(width 0.1524)
				(type default)
			)
			(layer "F.SilkS")
		)
		(fp_line
			(start 0.7874 0.4064)
			(end -0.7874 0.4064)
			(stroke
				(width 0.1524)
				(type default)
			)
			(layer "F.SilkS")
		)
		(fp_line
			(start -0.7874 -0.4064)
			(end 0.7874 -0.4064)
			(stroke
				(width 0.1524)
				(type default)
			)
			(layer "F.SilkS")
		)
		(fp_line
			(start 0.7874 -0.4064)
			(end 0.7874 0.4064)
			(stroke
				(width 0.1524)
				(type default)
			)
			(layer "F.SilkS")
		)
		(fp_line
			(start -0.67945 0.3048)
			(end -0.67945 -0.305054)
			(stroke
				(width 0.1)
				(type default)
			)
			(layer "F.Fab")
		)
		(fp_line
			(start -0.12065 0.3048)
			(end -0.67945 0.3048)
			(stroke
				(width 0.1)
				(type default)
			)
			(layer "F.Fab")
		)
		(fp_line
			(start 0.120396 0.3048)
			(end 0.120396 0.2794)
			(stroke
				(width 0.1)
				(type default)
			)
			(layer "F.Fab")
		)
		(fp_line
			(start 0.67945 0.3048)
			(end 0.120396 0.3048)
			(stroke
				(width 0.1)
				(type default)
			)
			(layer "F.Fab")
		)
		(fp_line
			(start -0.12065 0.2794)
			(end -0.12065 0.3048)
			(stroke
				(width 0.1)
				(type default)
			)
			(layer "F.Fab")
		)
		(fp_line
			(start 0.120396 0.2794)
			(end -0.12065 0.2794)
			(stroke
				(width 0.1)
				(type default)
			)
			(layer "F.Fab")
		)
		(fp_line
			(start -0.12065 -0.2794)
			(end 0.12065 -0.2794)
			(stroke
				(width 0.1)
				(type default)
			)
			(layer "F.Fab")
		)
		(fp_line
			(start 0.12065 -0.2794)
			(end 0.12065 -0.3048)
			(stroke
				(width 0.1)
				(type default)
			)
			(layer "F.Fab")
		)
		(fp_line
			(start 0.12065 -0.3048)
			(end 0.67945 -0.3048)
			(stroke
				(width 0.1)
				(type default)
			)
			(layer "F.Fab")
		)
		(fp_line
			(start 0.67945 -0.3048)
			(end 0.67945 0.3048)
			(stroke
				(width 0.1)
				(type default)
			)
			(layer "F.Fab")
		)
		(fp_line
			(start -0.67945 -0.305054)
			(end -0.12065 -0.305054)
			(stroke
				(width 0.1)
				(type default)
			)
			(layer "F.Fab")
		)
		(fp_line
			(start -0.12065 -0.305054)
			(end -0.12065 -0.2794)
			(stroke
				(width 0.1)
				(type default)
			)
			(layer "F.Fab")
		)
		(pad "1" smd circle
			(at -0.40005 0 270)
			(size 0 0)
			(layers "F.Cu" "F.Mask" "F.Paste")
			(net "GND")
		)
		(pad "2" smd circle
			(at 0.40005 0 270)
			(size 0 0)
			(layers "F.Cu" "F.Mask" "F.Paste")
			(net "PEX0_MODE_SEL7")
		)
	)
	(footprint ""
		(layer "F.Cu")
		(at 376.312684 -81.9658)
		(property "Reference" "R1752"
			(at 0 0 0)
			(layer "F.SilkS")
			(hide yes)
			(effects
				(font
					(size 1.27 1.27)
				)
			)
		)
		(property "Value" ""
			(at 0 0 0)
			(layer "F.Fab")
			(effects
				(font
					(size 1.27 1.27)
				)
			)
		)
		(duplicate_pad_numbers_are_jumpers no)
		(fp_line
			(start -0.7874 -0.4064)
			(end 0.7874 -0.4064)
			(stroke
				(width 0.1524)
				(type default)
			)
			(layer "F.SilkS")
		)
		(fp_line
			(start -0.7874 0.4064)
			(end -0.7874 -0.4064)
			(stroke
				(width 0.1524)
				(type default)
			)
			(layer "F.SilkS")
		)
		(fp_line
			(start 0.7874 -0.4064)
			(end 0.7874 0.4064)
			(stroke
				(width 0.1524)
				(type default)
			)
			(layer "F.SilkS")
		)
		(fp_line
			(start 0.7874 0.4064)
			(end -0.7874 0.4064)
			(stroke
				(width 0.1524)
				(type default)
			)
			(layer "F.SilkS")
		)
		(fp_line
			(start -0.67945 -0.305054)
			(end -0.12065 -0.305054)
			(stroke
				(width 0.1)
				(type default)
			)
			(layer "F.Fab")
		)
		(fp_line
			(start -0.67945 0.3048)
			(end -0.67945 -0.305054)
			(stroke
				(width 0.1)
				(type default)
			)
			(layer "F.Fab")
		)
		(fp_line
			(start -0.12065 -0.305054)
			(end -0.12065 -0.2794)
			(stroke
				(width 0.1)
				(type default)
			)
			(layer "F.Fab")
		)
		(fp_line
			(start -0.12065 -0.2794)
			(end 0.12065 -0.2794)
			(stroke
				(width 0.1)
				(type default)
			)
			(layer "F.Fab")
		)
		(fp_line
			(start -0.12065 0.2794)
			(end -0.12065 0.3048)
			(stroke
				(width 0.1)
				(type default)
			)
			(layer "F.Fab")
		)
		(fp_line
			(start -0.12065 0.3048)
			(end -0.67945 0.3048)
			(stroke
				(width 0.1)
				(type default)
			)
			(layer "F.Fab")
		)
		(fp_line
			(start 0.120396 0.2794)
			(end -0.12065 0.2794)
			(stroke
				(width 0.1)
				(type default)
			)
			(layer "F.Fab")
		)
		(fp_line
			(start 0.120396 0.3048)
			(end 0.120396 0.2794)
			(stroke
				(width 0.1)
				(type default)
			)
			(layer "F.Fab")
		)
		(fp_line
			(start 0.12065 -0.3048)
			(end 0.67945 -0.3048)
			(stroke
				(width 0.1)
				(type default)
			)
			(layer "F.Fab")
		)
		(fp_line
			(start 0.12065 -0.2794)
			(end 0.12065 -0.3048)
			(stroke
				(width 0.1)
				(type default)
			)
			(layer "F.Fab")
		)
		(fp_line
			(start 0.67945 -0.3048)
			(end 0.67945 0.3048)
			(stroke
				(width 0.1)
				(type default)
			)
			(layer "F.Fab")
		)
		(fp_line
			(start 0.67945 0.3048)
			(end 0.120396 0.3048)
			(stroke
				(width 0.1)
				(type default)
			)
			(layer "F.Fab")
		)
		(pad "1" smd circle
			(at -0.40005 0)
			(size 0 0)
			(layers "F.Cu" "F.Mask" "F.Paste")
			(net "P3V3_AUX")
		)
		(pad "2" smd circle
			(at 0.40005 0)
			(size 0 0)
			(layers "F.Cu" "F.Mask" "F.Paste")
			(net "SMB_BIC_I2C6_MUX_SSD_0_7_ADC_R_SDA")
		)
	)
	(footprint ""
		(layer "F.Cu")
		(at 25.524968 -343.952322 90)
		(property "Reference" "C2156"
			(at 0 0 90)
			(layer "F.SilkS")
			(hide yes)
			(effects
				(font
					(size 1.27 1.27)
				)
			)
		)
		(property "Value" ""
			(at 0 0 90)
			(layer "F.Fab")
			(effects
				(font
					(size 1.27 1.27)
				)
			)
		)
		(duplicate_pad_numbers_are_jumpers no)
		(fp_line
			(start 0.299974 -0.150114)
			(end 0.299974 0.150114)
			(stroke
				(width 0.1)
				(type default)
			)
			(layer "F.Fab")
		)
		(fp_line
			(start -0.299974 -0.150114)
			(end 0.299974 -0.150114)
			(stroke
				(width 0.1)
				(type default)
			)
			(layer "F.Fab")
		)
		(fp_line
			(start 0.299974 0.150114)
			(end -0.299974 0.150114)
			(stroke
				(width 0.1)
				(type default)
			)
			(layer "F.Fab")
		)
		(fp_line
			(start -0.299974 0.150114)
			(end -0.299974 -0.150114)
			(stroke
				(width 0.1)
				(type default)
			)
			(layer "F.Fab")
		)
		(pad "1" smd rect
			(at -0.2667 0 90)
			(size 0.3048 0.381)
			(layers "F.Cu" "F.Mask" "F.Paste")
			(net "P5E_PEX0_STN4_TX_DP<77>")
		)
		(pad "2" smd rect
			(at 0.2667 0 90)
			(size 0.3048 0.381)
			(layers "F.Cu" "F.Mask" "F.Paste")
			(net "P5E_PEX0_STN4_TX_C_DP<77>")
		)
	)
	(footprint ""
		(layer "F.Cu")
		(at 215.985598 -25.1587 -90)
		(property "Reference" "R5746"
			(at 0 0 270)
			(layer "F.SilkS")
			(hide yes)
			(effects
				(font
					(size 1.27 1.27)
				)
			)
		)
		(property "Value" ""
			(at 0 0 270)
			(layer "F.Fab")
			(effects
				(font
					(size 1.27 1.27)
				)
			)
		)
		(duplicate_pad_numbers_are_jumpers no)
		(fp_line
			(start -0.7874 0.4064)
			(end -0.7874 -0.4064)
			(stroke
				(width 0.1524)
				(type default)
			)
			(layer "F.SilkS")
		)
		(fp_line
			(start 0.7874 0.4064)
			(end -0.7874 0.4064)
			(stroke
				(width 0.1524)
				(type default)
			)
			(layer "F.SilkS")
		)
		(fp_line
			(start -0.7874 -0.4064)
			(end 0.7874 -0.4064)
			(stroke
				(width 0.1524)
				(type default)
			)
			(layer "F.SilkS")
		)
		(fp_line
			(start 0.7874 -0.4064)
			(end 0.7874 0.4064)
			(stroke
				(width 0.1524)
				(type default)
			)
			(layer "F.SilkS")
		)
		(fp_line
			(start -0.67945 0.3048)
			(end -0.67945 -0.305054)
			(stroke
				(width 0.1)
				(type default)
			)
			(layer "F.Fab")
		)
		(fp_line
			(start -0.12065 0.3048)
			(end -0.67945 0.3048)
			(stroke
				(width 0.1)
				(type default)
			)
			(layer "F.Fab")
		)
		(fp_line
			(start 0.120396 0.3048)
			(end 0.120396 0.2794)
			(stroke
				(width 0.1)
				(type default)
			)
			(layer "F.Fab")
		)
		(fp_line
			(start 0.67945 0.3048)
			(end 0.120396 0.3048)
			(stroke
				(width 0.1)
				(type default)
			)
			(layer "F.Fab")
		)
		(fp_line
			(start -0.12065 0.2794)
			(end -0.12065 0.3048)
			(stroke
				(width 0.1)
				(type default)
			)
			(layer "F.Fab")
		)
		(fp_line
			(start 0.120396 0.2794)
			(end -0.12065 0.2794)
			(stroke
				(width 0.1)
				(type default)
			)
			(layer "F.Fab")
		)
		(fp_line
			(start -0.12065 -0.2794)
			(end 0.12065 -0.2794)
			(stroke
				(width 0.1)
				(type default)
			)
			(layer "F.Fab")
		)
		(fp_line
			(start 0.12065 -0.2794)
			(end 0.12065 -0.3048)
			(stroke
				(width 0.1)
				(type default)
			)
			(layer "F.Fab")
		)
		(fp_line
			(start 0.12065 -0.3048)
			(end 0.67945 -0.3048)
			(stroke
				(width 0.1)
				(type default)
			)
			(layer "F.Fab")
		)
		(fp_line
			(start 0.67945 -0.3048)
			(end 0.67945 0.3048)
			(stroke
				(width 0.1)
				(type default)
			)
			(layer "F.Fab")
		)
		(fp_line
			(start -0.67945 -0.305054)
			(end -0.12065 -0.305054)
			(stroke
				(width 0.1)
				(type default)
			)
			(layer "F.Fab")
		)
		(fp_line
			(start -0.12065 -0.305054)
			(end -0.12065 -0.2794)
			(stroke
				(width 0.1)
				(type default)
			)
			(layer "F.Fab")
		)
		(pad "1" smd circle
			(at -0.40005 0 270)
			(size 0 0)
			(layers "F.Cu" "F.Mask" "F.Paste")
			(net "SSD7_LED_ISO_N")
		)
		(pad "2" smd circle
			(at 0.40005 0 270)
			(size 0 0)
			(layers "F.Cu" "F.Mask" "F.Paste")
			(net "SSD7_LED_ISO_R_N")
		)
	)
	(footprint ""
		(layer "F.Cu")
		(at 145.642076 -305.648106 -135)
		(property "Reference" "R1308"
			(at 0 0 225)
			(layer "F.SilkS")
			(hide yes)
			(effects
				(font
					(size 1.27 1.27)
				)
			)
		)
		(property "Value" ""
			(at 0 0 225)
			(layer "F.Fab")
			(effects
				(font
					(size 1.27 1.27)
				)
			)
		)
		(duplicate_pad_numbers_are_jumpers no)
		(fp_line
			(start 0.787389 0.406267)
			(end -0.787389 0.406267)
			(stroke
				(width 0.1524)
				(type default)
			)
			(layer "F.SilkS")
		)
		(fp_line
			(start 0.787389 -0.406267)
			(end 0.787389 0.406267)
			(stroke
				(width 0.1524)
				(type default)
			)
			(layer "F.SilkS")
		)
		(fp_line
			(start -0.787389 0.406267)
			(end -0.787389 -0.406267)
			(stroke
				(width 0.1524)
				(type default)
			)
			(layer "F.SilkS")
		)
		(fp_line
			(start -0.787389 -0.406267)
			(end 0.787389 -0.406267)
			(stroke
				(width 0.1524)
				(type default)
			)
			(layer "F.SilkS")
		)
		(fp_line
			(start 0.679446 0.30479)
			(end 0.120515 0.30479)
			(stroke
				(width 0.1)
				(type default)
			)
			(layer "F.Fab")
		)
		(fp_line
			(start 0.120515 0.30479)
			(end 0.120335 0.279466)
			(stroke
				(width 0.1)
				(type default)
			)
			(layer "F.Fab")
		)
		(fp_line
			(start 0.120335 0.279466)
			(end -0.120695 0.279466)
			(stroke
				(width 0.1)
				(type default)
			)
			(layer "F.Fab")
		)
		(fp_line
			(start 0.679446 -0.30479)
			(end 0.679446 0.30479)
			(stroke
				(width 0.1)
				(type default)
			)
			(layer "F.Fab")
		)
		(fp_line
			(start -0.120515 0.30479)
			(end -0.679446 0.30479)
			(stroke
				(width 0.1)
				(type default)
			)
			(layer "F.Fab")
		)
		(fp_line
			(start -0.120695 0.279466)
			(end -0.120515 0.30479)
			(stroke
				(width 0.1)
				(type default)
			)
			(layer "F.Fab")
		)
		(fp_line
			(start 0.120695 -0.279466)
			(end 0.120515 -0.30479)
			(stroke
				(width 0.1)
				(type default)
			)
			(layer "F.Fab")
		)
		(fp_line
			(start 0.120515 -0.30479)
			(end 0.679446 -0.30479)
			(stroke
				(width 0.1)
				(type default)
			)
			(layer "F.Fab")
		)
		(fp_line
			(start -0.679446 0.30479)
			(end -0.679446 -0.305149)
			(stroke
				(width 0.1)
				(type default)
			)
			(layer "F.Fab")
		)
		(fp_line
			(start -0.120695 -0.279466)
			(end 0.120695 -0.279466)
			(stroke
				(width 0.1)
				(type default)
			)
			(layer "F.Fab")
		)
		(fp_line
			(start -0.120695 -0.304969)
			(end -0.120695 -0.279466)
			(stroke
				(width 0.1)
				(type default)
			)
			(layer "F.Fab")
		)
		(fp_line
			(start -0.679446 -0.305149)
			(end -0.120695 -0.304969)
			(stroke
				(width 0.1)
				(type default)
			)
			(layer "F.Fab")
		)
		(pad "1" smd circle
			(at -0.40005 0 225)
			(size 0 0)
			(layers "F.Cu" "F.Mask" "F.Paste")
			(net "PEX1_DFT_IDDT")
		)
		(pad "2" smd circle
			(at 0.40005 0 225)
			(size 0 0)
			(layers "F.Cu" "F.Mask" "F.Paste")
			(net "P1V8_PEX")
		)
	)
)
